# T6G (Grand Teton) — schematic netlist excerpt (pin names and nets, part order shuffled) for the footprints in the layout excerpt that follows; sources: Cadence DE-HDL packaged netlist, KiCad conversion of 04192023_DAF0TMB3IC0_F0TG_MB_C_brd_V02_OCP.brd

R6732  Q_RES  0 5% CHIP  pkg 0201LF  page 332 : A = NCF_A1_CPU1_P1_GND ; B = GND
R903  Q_RES  1K 1% EMPTY  pkg 0201LF  page 353 : A = RT_CPU1_P3_ADDR3 ; B = GND
R822  Q_RES  10K 5% CHIP  pkg 0402LF  page 164 : A = P3V3_AUX ; B = UART_CPU0_SCM_LVC3_UART1_TX

(kicad_pcb
	(version 20260206)
	(generator "pcbnew")
	(generator_version "10.0")
	(general
		(thickness 1.6)
		(legacy_teardrops no)
	)
	(paper "A4")
	(title_block
		(title "04192023_DAF0TMB3IC0_F0TG_MB_C_brd_V02_OCP.brd")
		(comment 1 "Grand Teton / footprints 113-115 of 8354")
	)
	(layers
		(0 "F.Cu" signal "TOP")
		(4 "In1.Cu" signal "GND")
		(6 "In2.Cu" signal "IN1")
		(8 "In3.Cu" signal "GND1")
		(10 "In4.Cu" signal "IN2")
		(12 "In5.Cu" signal "GND2")
		(14 "In6.Cu" signal "IN3")
		(16 "In7.Cu" signal "GND3")
		(18 "In8.Cu" signal "VCC")
		(20 "In9.Cu" signal "VCC1")
		(22 "In10.Cu" signal "GND4")
		(24 "In11.Cu" signal "IN4")
		(26 "In12.Cu" signal "GND5")
		(28 "In13.Cu" signal "IN5")
		(30 "In14.Cu" signal "GND6")
		(32 "In15.Cu" signal "IN6")
		(34 "In16.Cu" signal "GND7")
		(2 "B.Cu" signal "BOTTOM")
		(9 "F.Adhes" user "F.Adhesive")
		(11 "B.Adhes" user "B.Adhesive")
		(13 "F.Paste" user "Package Geometry/Pastemask Top")
		(15 "B.Paste" user "Package Geometry/Pastemask Bottom")
		(5 "F.SilkS" user "Ref Des/Silkscreen Top")
		(7 "B.SilkS" user "Ref Des/Silkscreen Bottom")
		(1 "F.Mask" user "Board Geometry/Soldermask Top")
		(3 "B.Mask" user "Board Geometry/Soldermask Bottom")
		(17 "Dwgs.User" user "User.Drawings")
		(19 "Cmts.User" user "User.Comments")
		(21 "Eco1.User" user "User.Eco1")
		(23 "Eco2.User" user "User.Eco2")
		(25 "Edge.Cuts" user "Board Geometry/Outline")
		(27 "Margin" user)
		(31 "F.CrtYd" user "Package Geometry/Place Bound Top")
		(29 "B.CrtYd" user "Package Geometry/Place Bound Bottom")
		(35 "F.Fab" user "Ref Des/Assembly Top")
		(33 "B.Fab" user "Ref Des/Assembly Bottom")
	)
	(footprint ""
		(layer "F.Cu")
		(at 101.509068 -394.3604 -90)
		(property "Reference" "R6732"
			(at 0 0 270)
			(layer "F.SilkS")
			(hide yes)
			(effects
				(font
					(size 1.27 1.27)
				)
			)
		)
		(property "Value" ""
			(at 0 0 270)
			(layer "F.Fab")
			(effects
				(font
					(size 1.27 1.27)
				)
			)
		)
		(duplicate_pad_numbers_are_jumpers no)
		(fp_line
			(start -0.32512 0.175006)
			(end -0.32512 -0.175006)
			(stroke
				(width 0.1)
				(type default)
			)
			(layer "F.Fab")
		)
		(fp_line
			(start 0.32512 0.175006)
			(end -0.32512 0.175006)
			(stroke
				(width 0.1)
				(type default)
			)
			(layer "F.Fab")
		)
		(fp_line
			(start -0.32512 -0.175006)
			(end 0.32512 -0.175006)
			(stroke
				(width 0.1)
				(type default)
			)
			(layer "F.Fab")
		)
		(fp_line
			(start 0.32512 -0.175006)
			(end 0.32512 0.175006)
			(stroke
				(width 0.1)
				(type default)
			)
			(layer "F.Fab")
		)
		(pad "1" smd rect
			(at -0.2667 0 270)
			(size 0.3048 0.381)
			(layers "F.Cu" "F.Mask" "F.Paste")
			(net "NCF_A1_CPU1_P1_GND")
		)
		(pad "2" smd rect
			(at 0.2667 0 90)
			(size 0.3048 0.381)
			(layers "F.Cu" "F.Mask" "F.Paste")
			(net "GND")
		)
	)
	(footprint ""
		(layer "F.Cu")
		(at 138.981942 -386.7912 90)
		(property "Reference" "R903"
			(at 0 0 90)
			(layer "F.SilkS")
			(hide yes)
			(effects
				(font
					(size 1.27 1.27)
				)
			)
		)
		(property "Value" ""
			(at 0 0 90)
			(layer "F.Fab")
			(effects
				(font
					(size 1.27 1.27)
				)
			)
		)
		(duplicate_pad_numbers_are_jumpers no)
		(fp_line
			(start 0.32512 -0.175006)
			(end 0.32512 0.175006)
			(stroke
				(width 0.1)
				(type default)
			)
			(layer "F.Fab")
		)
		(fp_line
			(start -0.32512 -0.175006)
			(end 0.32512 -0.175006)
			(stroke
				(width 0.1)
				(type default)
			)
			(layer "F.Fab")
		)
		(fp_line
			(start 0.32512 0.175006)
			(end -0.32512 0.175006)
			(stroke
				(width 0.1)
				(type default)
			)
			(layer "F.Fab")
		)
		(fp_line
			(start -0.32512 0.175006)
			(end -0.32512 -0.175006)
			(stroke
				(width 0.1)
				(type default)
			)
			(layer "F.Fab")
		)
		(pad "1" smd rect
			(at -0.2667 0 90)
			(size 0.3048 0.381)
			(layers "F.Cu" "F.Mask" "F.Paste")
			(net "RT_CPU1_P3_ADDR3")
		)
		(pad "2" smd rect
			(at 0.2667 0 270)
			(size 0.3048 0.381)
			(layers "F.Cu" "F.Mask" "F.Paste")
			(net "GND")
		)
	)
	(footprint ""
		(layer "F.Cu")
		(at 369.455446 -28.306522 90)
		(property "Reference" "R822"
			(at 0 0 90)
			(layer "F.SilkS")
			(hide yes)
			(effects
				(font
					(size 1.27 1.27)
				)
			)
		)
		(property "Value" ""
			(at 0 0 90)
			(layer "F.Fab")
			(effects
				(font
					(size 1.27 1.27)
				)
			)
		)
		(duplicate_pad_numbers_are_jumpers no)
		(fp_line
			(start 0.7874 -0.4064)
			(end 0.7874 0.4064)
			(stroke
				(width 0.1524)
				(type default)
			)
			(layer "F.SilkS")
		)
		(fp_line
			(start -0.7874 -0.4064)
			(end 0.7874 -0.4064)
			(stroke
				(width 0.1524)
				(type default)
			)
			(layer "F.SilkS")
		)
		(fp_line
			(start 0.7874 0.4064)
			(end -0.7874 0.4064)
			(stroke
				(width 0.1524)
				(type default)
			)
			(layer "F.SilkS")
		)
		(fp_line
			(start -0.7874 0.4064)
			(end -0.7874 -0.4064)
			(stroke
				(width 0.1524)
				(type default)
			)
			(layer "F.SilkS")
		)
		(fp_line
			(start -0.12065 -0.305054)
			(end -0.12065 -0.2794)
			(stroke
				(width 0.1)
				(type default)
			)
			(layer "F.Fab")
		)
		(fp_line
			(start -0.67945 -0.305054)
			(end -0.12065 -0.305054)
			(stroke
				(width 0.1)
				(type default)
			)
			(layer "F.Fab")
		)
		(fp_line
			(start 0.67945 -0.3048)
			(end 0.67945 0.3048)
			(stroke
				(width 0.1)
				(type default)
			)
			(layer "F.Fab")
		)
		(fp_line
			(start 0.12065 -0.3048)
			(end 0.67945 -0.3048)
			(stroke
				(width 0.1)
				(type default)
			)
			(layer "F.Fab")
		)
		(fp_line
			(start 0.12065 -0.2794)
			(end 0.12065 -0.3048)
			(stroke
				(width 0.1)
				(type default)
			)
			(layer "F.Fab")
		)
		(fp_line
			(start -0.12065 -0.2794)
			(end 0.12065 -0.2794)
			(stroke
				(width 0.1)
				(type default)
			)
			(layer "F.Fab")
		)
		(fp_line
			(start 0.120396 0.2794)
			(end -0.12065 0.2794)
			(stroke
				(width 0.1)
				(type default)
			)
			(layer "F.Fab")
		)
		(fp_line
			(start -0.12065 0.2794)
			(end -0.12065 0.3048)
			(stroke
				(width 0.1)
				(type default)
			)
			(layer "F.Fab")
		)
		(fp_line
			(start 0.67945 0.3048)
			(end 0.120396 0.3048)
			(stroke
				(width 0.1)
				(type default)
			)
			(layer "F.Fab")
		)
		(fp_line
			(start 0.120396 0.3048)
			(end 0.120396 0.2794)
			(stroke
				(width 0.1)
				(type default)
			)
			(layer "F.Fab")
		)
		(fp_line
			(start -0.12065 0.3048)
			(end -0.67945 0.3048)
			(stroke
				(width 0.1)
				(type default)
			)
			(layer "F.Fab")
		)
		(fp_line
			(start -0.67945 0.3048)
			(end -0.67945 -0.305054)
			(stroke
				(width 0.1)
				(type default)
			)
			(layer "F.Fab")
		)
		(pad "1" smd circle
			(at -0.40005 0 90)
			(size 0 0)
			(layers "F.Cu" "F.Mask" "F.Paste")
			(net "P3V3_AUX")
		)
		(pad "2" smd circle
			(at 0.40005 0 90)
			(size 0 0)
			(layers "F.Cu" "F.Mask" "F.Paste")
			(net "UART_CPU0_SCM_LVC3_UART1_TX")
		)
	)
)
